(kicad_pcb
	(version 20260206)
	(generator "pcbnew")
	(generator_version "10.0")
	(general
		(thickness 1.6)
		(legacy_teardrops no)
	)
	(paper "A4")
	(title_block
		(title "Bryce Canyon_SCC_16316-1_OCP.brd")
		(comment 1 "Bryce Canyon / footprints 80-86 of 1561")
	)
	(layers
		(0 "F.Cu" signal "TOP")
		(4 "In1.Cu" signal "L2GND")
		(6 "In2.Cu" signal "L3")
		(8 "In3.Cu" signal "L4VCC")
		(10 "In4.Cu" signal "L5VCC")
		(12 "In5.Cu" signal "L6")
		(14 "In6.Cu" signal "L7GND")
		(2 "B.Cu" signal "BOTTOM")
		(9 "F.Adhes" user "F.Adhesive")
		(11 "B.Adhes" user "B.Adhesive")
		(13 "F.Paste" user "Package Geometry/Pastemask Top")
		(15 "B.Paste" user "Package Geometry/Pastemask Bottom")
		(5 "F.SilkS" user "Ref Des/Silkscreen Top")
		(7 "B.SilkS" user "Ref Des/Silkscreen Bottom")
		(1 "F.Mask" user "Board Geometry/Soldermask Top")
		(3 "B.Mask" user "Board Geometry/Soldermask Bottom")
		(17 "Dwgs.User" user "User.Drawings")
		(19 "Cmts.User" user "User.Comments")
		(21 "Eco1.User" user "User.Eco1")
		(23 "Eco2.User" user "User.Eco2")
		(25 "Edge.Cuts" user "Board Geometry/Outline")
		(27 "Margin" user)
		(31 "F.CrtYd" user "Package Geometry/Place Bound Top")
		(29 "B.CrtYd" user "Package Geometry/Place Bound Bottom")
		(35 "F.Fab" user "Ref Des/Assembly Top")
		(33 "B.Fab" user "Ref Des/Assembly Bottom")
	)
	(footprint ""
		(layer "F.Cu")
		(at 166.233856 -58.11901)
		(property "Reference" "R263"
			(at 0 0 0)
			(layer "F.SilkS")
			(hide yes)
			(effects
				(font
					(size 1.27 1.27)
				)
			)
		)
		(property "Value" "4K7R2F-GP"
			(at 0.064008 -3.993896 0)
			(unlocked yes)
			(layer "F.Fab")
			(hide yes)
			(effects
				(font
					(size 1.016 1.016)
					(thickness 0.1524)
				)
			)
		)
		(property "Device Type" "R402H16"
			(at 0.064008 -5.517896 0)
			(unlocked yes)
			(layer "F.Fab")
			(hide yes)
			(effects
				(font
					(size 1.016 1.016)
					(thickness 0.1524)
				)
			)
		)
		(duplicate_pad_numbers_are_jumpers no)
		(fp_line
			(start -0.508 -0.9398)
			(end -0.508 0.9398)
			(stroke
				(width 0.1524)
				(type default)
			)
			(layer "F.SilkS")
		)
		(fp_line
			(start 0.508 -0.9398)
			(end -0.508 -0.9398)
			(stroke
				(width 0.1524)
				(type default)
			)
			(layer "F.SilkS")
		)
		(fp_rect
			(start -0.508 0.9398)
			(end 0.508 -0.9398)
			(stroke
				(width 0)
				(type default)
			)
			(fill no)
			(layer "F.CrtYd")
		)
		(fp_rect
			(start -0.508 0.9398)
			(end 0.508 -0.9398)
			(stroke
				(width 0)
				(type default)
			)
			(fill no)
			(layer "F.Fab")
		)
		(pad "1" smd custom
			(at 0 -0.4445)
			(size 0.1397 0.1397)
			(layers "F.Cu" "F.Mask" "F.Paste")
			(net "P1V8_C")
			(options
				(clearance outline)
				(anchor circle)
			)
			(primitives
				(gr_poly
					(pts
						(arc
							(start -0.1778 -0.2794)
							(mid -0.249642 -0.249642)
							(end -0.2794 -0.1778)
						)
						(arc
							(start -0.2794 0.1778)
							(mid -0.249642 0.249642)
							(end -0.1778 0.2794)
						)
						(arc
							(start 0.1778 0.2794)
							(mid 0.249642 0.249642)
							(end 0.2794 0.1778)
						)
						(arc
							(start 0.2794 -0.1778)
							(mid 0.249642 -0.249642)
							(end 0.1778 -0.2794)
						)
					)
					(width 0)
					(fill yes)
				)
			)
		)
		(pad "2" smd custom
			(at 0 0.4445)
			(size 0.1397 0.1397)
			(layers "F.Cu" "F.Mask" "F.Paste")
			(net "ICE1_TCK")
			(options
				(clearance outline)
				(anchor circle)
			)
			(primitives
				(gr_poly
					(pts
						(arc
							(start -0.1778 -0.2794)
							(mid -0.249642 -0.249642)
							(end -0.2794 -0.1778)
						)
						(arc
							(start -0.2794 0.1778)
							(mid -0.249642 0.249642)
							(end -0.1778 0.2794)
						)
						(arc
							(start 0.1778 0.2794)
							(mid 0.249642 0.249642)
							(end 0.2794 0.1778)
						)
						(arc
							(start 0.2794 -0.1778)
							(mid 0.249642 -0.249642)
							(end 0.1778 -0.2794)
						)
					)
					(width 0)
					(fill yes)
				)
			)
		)
	)
	(footprint ""
		(layer "F.Cu")
		(at 139.050522 -76.52512 180)
		(property "Reference" "VIA25"
			(at 0 0 180)
			(layer "F.SilkS")
			(hide yes)
			(effects
				(font
					(size 1.27 1.27)
				)
			)
		)
		(property "Value" "100OHM-8L-1D6MM-L18L16-GP"
			(at -3.7211 -4.5085 180)
			(unlocked yes)
			(layer "F.Fab")
			(hide yes)
			(effects
				(font
					(size 1.016 1.016)
					(thickness 0.1524)
				)
			)
		)
		(property "Device Type" "VIA-PCIE-4P-394076"
			(at -3.7211 -6.0325 180)
			(unlocked yes)
			(layer "F.Fab")
			(hide yes)
			(effects
				(font
					(size 1.016 1.016)
					(thickness 0.1524)
				)
			)
		)
		(duplicate_pad_numbers_are_jumpers no)
		(fp_rect
			(start -1.9685 0.381)
			(end 1.9685 -0.381)
			(stroke
				(width 0)
				(type default)
			)
			(fill no)
			(layer "F.CrtYd")
		)
		(fp_rect
			(start -1.9685 0.381)
			(end 1.9685 -0.381)
			(stroke
				(width 0)
				(type default)
			)
			(fill no)
			(layer "F.Fab")
		)
		(pad "1" thru_hole circle
			(at -1.5875 0 180)
			(size 0.508 0.508)
			(drill 0.254)
			(layers "*.Cu" "*.Mask")
			(remove_unused_layers no)
			(net "GND")
			(clearance 0.127)
			(thermal_gap 0.127)
		)
		(pad "2" thru_hole circle
			(at -0.5715 0 180)
			(size 0.508 0.508)
			(drill 0.254)
			(layers "*.Cu" "*.Mask")
			(remove_unused_layers no)
			(net "PHY_EXP_TO_CONN_8_DP")
			(clearance 0.127)
			(thermal_gap 0.127)
		)
		(pad "3" thru_hole circle
			(at 0.5715 0 180)
			(size 0.508 0.508)
			(drill 0.254)
			(layers "*.Cu" "*.Mask")
			(remove_unused_layers no)
			(net "PHY_EXP_TO_CONN_8_DN")
			(clearance 0.127)
			(thermal_gap 0.127)
		)
		(pad "4" thru_hole circle
			(at 1.5875 0 180)
			(size 0.508 0.508)
			(drill 0.254)
			(layers "*.Cu" "*.Mask")
			(remove_unused_layers no)
			(net "GND")
			(clearance 0.127)
			(thermal_gap 0.127)
		)
	)
	(footprint ""
		(layer "F.Cu")
		(at 173.99 -110.0582 90)
		(property "Reference" "R92"
			(at 0 0 90)
			(layer "F.SilkS")
			(hide yes)
			(effects
				(font
					(size 1.27 1.27)
				)
			)
		)
		(property "Value" "0R2J-2-GP"
			(at 0.064008 -3.993896 90)
			(unlocked yes)
			(layer "F.Fab")
			(hide yes)
			(effects
				(font
					(size 1.016 1.016)
					(thickness 0.1524)
				)
			)
		)
		(property "Device Type" "R402H16"
			(at 0.064008 -5.517896 90)
			(unlocked yes)
			(layer "F.Fab")
			(hide yes)
			(effects
				(font
					(size 1.016 1.016)
					(thickness 0.1524)
				)
			)
		)
		(duplicate_pad_numbers_are_jumpers no)
		(fp_line
			(start 0.508 -0.9398)
			(end -0.508 -0.9398)
			(stroke
				(width 0.1524)
				(type default)
			)
			(layer "F.SilkS")
		)
		(fp_line
			(start -0.508 -0.9398)
			(end -0.508 0.9398)
			(stroke
				(width 0.1524)
				(type default)
			)
			(layer "F.SilkS")
		)
		(fp_rect
			(start -0.508 0.9398)
			(end 0.508 -0.9398)
			(stroke
				(width 0)
				(type default)
			)
			(fill no)
			(layer "F.CrtYd")
		)
		(fp_rect
			(start -0.508 0.9398)
			(end 0.508 -0.9398)
			(stroke
				(width 0)
				(type default)
			)
			(fill no)
			(layer "F.Fab")
		)
		(pad "1" smd custom
			(at 0 -0.4445 90)
			(size 0.1397 0.1397)
			(layers "F.Cu" "F.Mask" "F.Paste")
			(net "SCC_FULL_PWR_BUF_EN")
			(options
				(clearance outline)
				(anchor circle)
			)
			(primitives
				(gr_poly
					(pts
						(arc
							(start -0.1778 -0.2794)
							(mid -0.249642 -0.249642)
							(end -0.2794 -0.1778)
						)
						(arc
							(start -0.2794 0.1778)
							(mid -0.249642 0.249642)
							(end -0.1778 0.2794)
						)
						(arc
							(start 0.1778 0.2794)
							(mid 0.249642 0.249642)
							(end 0.2794 0.1778)
						)
						(arc
							(start 0.2794 -0.1778)
							(mid 0.249642 -0.249642)
							(end 0.1778 -0.2794)
						)
					)
					(width 0)
					(fill yes)
				)
			)
		)
		(pad "2" smd custom
			(at 0 0.4445 90)
			(size 0.1397 0.1397)
			(layers "F.Cu" "F.Mask" "F.Paste")
			(net "P1V8_E_EN")
			(options
				(clearance outline)
				(anchor circle)
			)
			(primitives
				(gr_poly
					(pts
						(arc
							(start -0.1778 -0.2794)
							(mid -0.249642 -0.249642)
							(end -0.2794 -0.1778)
						)
						(arc
							(start -0.2794 0.1778)
							(mid -0.249642 0.249642)
							(end -0.1778 0.2794)
						)
						(arc
							(start 0.1778 0.2794)
							(mid 0.249642 0.249642)
							(end 0.2794 0.1778)
						)
						(arc
							(start 0.2794 -0.1778)
							(mid 0.249642 -0.249642)
							(end 0.1778 -0.2794)
						)
					)
					(width 0)
					(fill yes)
				)
			)
		)
	)
	(footprint ""
		(layer "F.Cu")
		(at 145.249138 -32.979614 102)
		(property "Reference" "C327"
			(at 0 0 102)
			(layer "F.SilkS")
			(hide yes)
			(effects
				(font
					(size 1.27 1.27)
				)
			)
		)
		(property "Value" "SCD01U16V1KX-GP"
			(at -2.831995 -1.740026 102)
			(unlocked yes)
			(layer "F.Fab")
			(hide yes)
			(effects
				(font
					(size 1.016 1.016)
					(thickness 0.1524)
				)
			)
		)
		(property "Device Type" "C0201H13"
			(at -2.832121 -3.264082 102)
			(unlocked yes)
			(layer "F.Fab")
			(hide yes)
			(effects
				(font
					(size 1.016 1.016)
					(thickness 0.1524)
				)
			)
		)
		(duplicate_pad_numbers_are_jumpers no)
		(fp_poly
			(pts
				(xy -0.279454 -0.647706) (xy 0.279346 -0.647706) (xy 0.279346 0.647694) (xy -0.279454 0.647694)
			)
			(stroke
				(width 0)
				(type default)
			)
			(fill no)
			(layer "F.CrtYd")
		)
		(fp_poly
			(pts
				(xy -0.279454 -0.647706) (xy 0.279346 -0.647706) (xy 0.279346 0.647694) (xy -0.279454 0.647694)
			)
			(stroke
				(width 0)
				(type default)
			)
			(fill no)
			(layer "F.Fab")
		)
		(pad "1" smd custom
			(at -0.000001 -0.2794 102)
			(size 0.0762 0.0762)
			(layers "F.Cu" "F.Mask" "F.Paste")
			(net "PHY_SCC_TO_IOC_40_DP")
			(options
				(clearance outline)
				(anchor circle)
			)
			(primitives
				(gr_poly
					(pts
						(arc
							(start 0.1524 -0.127)
							(mid 0.137521 -0.162921)
							(end 0.1016 -0.1778)
						)
						(arc
							(start -0.1016 -0.1778)
							(mid -0.137521 -0.162921)
							(end -0.1524 -0.127)
						)
						(arc
							(start -0.1524 0.127)
							(mid -0.137521 0.162921)
							(end -0.1016 0.1778)
						)
						(arc
							(start 0.1016 0.1778)
							(mid 0.137521 0.162921)
							(end 0.1524 0.127)
						)
					)
					(width 0)
					(fill yes)
				)
			)
		)
		(pad "2" smd custom
			(at 0.000001 0.2794 102)
			(size 0.0762 0.0762)
			(layers "F.Cu" "F.Mask" "F.Paste")
			(net "PHY_SCC_TO_IOC_C_40_DP")
			(options
				(clearance outline)
				(anchor circle)
			)
			(primitives
				(gr_poly
					(pts
						(arc
							(start 0.1524 -0.127)
							(mid 0.137521 -0.162921)
							(end 0.1016 -0.1778)
						)
						(arc
							(start -0.1016 -0.1778)
							(mid -0.137521 -0.162921)
							(end -0.1524 -0.127)
						)
						(arc
							(start -0.1524 0.127)
							(mid -0.137521 0.162921)
							(end -0.1016 0.1778)
						)
						(arc
							(start 0.1016 0.1778)
							(mid 0.137521 0.162921)
							(end 0.1524 0.127)
						)
					)
					(width 0)
					(fill yes)
				)
			)
		)
	)
	(footprint ""
		(layer "F.Cu")
		(at 65.7098 -76.8604 180)
		(property "Reference" "R438"
			(at 0 0 180)
			(layer "F.SilkS")
			(hide yes)
			(effects
				(font
					(size 1.27 1.27)
				)
			)
		)
		(property "Value" "200KR2F-L-GP"
			(at 0.064008 -3.993896 180)
			(unlocked yes)
			(layer "F.Fab")
			(hide yes)
			(effects
				(font
					(size 1.016 1.016)
					(thickness 0.1524)
				)
			)
		)
		(property "Device Type" "R402H16"
			(at 0.064008 -5.517896 180)
			(unlocked yes)
			(layer "F.Fab")
			(hide yes)
			(effects
				(font
					(size 1.016 1.016)
					(thickness 0.1524)
				)
			)
		)
		(duplicate_pad_numbers_are_jumpers no)
		(fp_line
			(start 0.508 -0.9398)
			(end -0.508 -0.9398)
			(stroke
				(width 0.1524)
				(type default)
			)
			(layer "F.SilkS")
		)
		(fp_line
			(start -0.508 -0.9398)
			(end -0.508 0.9398)
			(stroke
				(width 0.1524)
				(type default)
			)
			(layer "F.SilkS")
		)
		(fp_rect
			(start -0.508 0.9398)
			(end 0.508 -0.9398)
			(stroke
				(width 0)
				(type default)
			)
			(fill no)
			(layer "F.CrtYd")
		)
		(fp_rect
			(start -0.508 0.9398)
			(end 0.508 -0.9398)
			(stroke
				(width 0)
				(type default)
			)
			(fill no)
			(layer "F.Fab")
		)
		(pad "1" smd custom
			(at 0 -0.4445 180)
			(size 0.1397 0.1397)
			(layers "F.Cu" "F.Mask" "F.Paste")
			(net "LS_EN_U38")
			(options
				(clearance outline)
				(anchor circle)
			)
			(primitives
				(gr_poly
					(pts
						(arc
							(start -0.1778 -0.2794)
							(mid -0.249642 -0.249642)
							(end -0.2794 -0.1778)
						)
						(arc
							(start -0.2794 0.1778)
							(mid -0.249642 0.249642)
							(end -0.1778 0.2794)
						)
						(arc
							(start 0.1778 0.2794)
							(mid 0.249642 0.249642)
							(end 0.2794 0.1778)
						)
						(arc
							(start 0.2794 -0.1778)
							(mid 0.249642 -0.249642)
							(end 0.1778 -0.2794)
						)
					)
					(width 0)
					(fill yes)
				)
			)
		)
		(pad "2" smd custom
			(at 0 0.4445 180)
			(size 0.1397 0.1397)
			(layers "F.Cu" "F.Mask" "F.Paste")
			(net "P0V9_PG")
			(options
				(clearance outline)
				(anchor circle)
			)
			(primitives
				(gr_poly
					(pts
						(arc
							(start -0.1778 -0.2794)
							(mid -0.249642 -0.249642)
							(end -0.2794 -0.1778)
						)
						(arc
							(start -0.2794 0.1778)
							(mid -0.249642 0.249642)
							(end -0.1778 0.2794)
						)
						(arc
							(start 0.1778 0.2794)
							(mid 0.249642 0.249642)
							(end 0.2794 0.1778)
						)
						(arc
							(start 0.2794 -0.1778)
							(mid 0.249642 -0.249642)
							(end 0.1778 -0.2794)
						)
					)
					(width 0)
					(fill yes)
				)
			)
		)
	)
	(footprint ""
		(layer "F.Cu")
		(at 83.80095 -108.181394)
		(property "Reference" "U48"
			(at 0 0 0)
			(layer "F.SilkS")
			(hide yes)
			(effects
				(font
					(size 1.27 1.27)
				)
			)
		)
		(property "Value" "SNLVC1G126DCKR-GP"
			(at -2.3368 -8.6868 0)
			(unlocked yes)
			(layer "F.Fab")
			(hide yes)
			(effects
				(font
					(size 1.016 1.016)
					(thickness 0.1524)
				)
			)
		)
		(property "Device Type" "SC70-5H44"
			(at -2.3114 -10.414 0)
			(unlocked yes)
			(layer "F.Fab")
			(hide yes)
			(effects
				(font
					(size 1.016 1.016)
					(thickness 0.1524)
				)
			)
		)
		(duplicate_pad_numbers_are_jumpers no)
		(fp_line
			(start -1.27 -1.7018)
			(end 1.27 -1.7018)
			(stroke
				(width 0.1524)
				(type default)
			)
			(layer "F.SilkS")
		)
		(fp_line
			(start -1.27 1.7018)
			(end -1.27 -1.7018)
			(stroke
				(width 0.1524)
				(type default)
			)
			(layer "F.SilkS")
		)
		(fp_line
			(start 0.6604 -1.8034)
			(end 1.3843 -1.8034)
			(stroke
				(width 0.3302)
				(type default)
			)
			(layer "F.SilkS")
		)
		(fp_line
			(start 1.27 -1.7018)
			(end 1.27 1.7018)
			(stroke
				(width 0.1524)
				(type default)
			)
			(layer "F.SilkS")
		)
		(fp_line
			(start 1.27 1.7018)
			(end -1.27 1.7018)
			(stroke
				(width 0.1524)
				(type default)
			)
			(layer "F.SilkS")
		)
		(fp_line
			(start 1.3843 -1.8034)
			(end 1.3843 -1.1176)
			(stroke
				(width 0.3302)
				(type default)
			)
			(layer "F.SilkS")
		)
		(fp_rect
			(start -1.524 1.9558)
			(end 1.524 -1.9558)
			(stroke
				(width 0)
				(type default)
			)
			(fill no)
			(layer "F.CrtYd")
		)
		(fp_poly
			(pts
				(xy -1.524 -1.9558) (xy 1.524 -1.9558) (xy 1.524 1.9558) (xy -1.524 1.9558)
			)
			(stroke
				(width 0)
				(type default)
			)
			(fill no)
			(layer "F.Fab")
		)
		(pad "1" smd rect
			(at 0.65024 -0.8255)
			(size 0.4064 1.2192)
			(layers "F.Cu" "F.Mask" "F.Paste")
			(net "U48_OE")
		)
		(pad "2" smd rect
			(at 0 -0.8255)
			(size 0.4064 1.2192)
			(layers "F.Cu" "F.Mask" "F.Paste")
			(net "SCC_FULL_PWR_EN_U48")
		)
		(pad "3" smd rect
			(at -0.65024 -0.8255)
			(size 0.4064 1.2192)
			(layers "F.Cu" "F.Mask" "F.Paste")
			(net "GND")
		)
		(pad "4" smd rect
			(at -0.65024 0.8255)
			(size 0.4064 1.2192)
			(layers "F.Cu" "F.Mask" "F.Paste")
			(net "SCC_FULL_PWR_BUF_EN_U48")
		)
		(pad "5" smd rect
			(at 0.65024 0.8255)
			(size 0.4064 1.2192)
			(layers "F.Cu" "F.Mask" "F.Paste")
			(net "P3V3")
		)
	)
	(footprint ""
		(layer "F.Cu")
		(at 58.547 -100.318316 90)
		(property "Reference" "R516"
			(at 0 0 90)
			(layer "F.SilkS")
			(hide yes)
			(effects
				(font
					(size 1.27 1.27)
				)
			)
		)
		(property "Value" "3D01R5F-GP"
			(at 0 -8.9535 90)
			(unlocked yes)
			(layer "F.Fab")
			(hide yes)
			(effects
				(font
					(size 1.27 1.016)
					(thickness 0.1524)
				)
			)
		)
		(property "Device Type" "R805H24"
			(at 0 -10.6299 90)
			(unlocked yes)
			(layer "F.Fab")
			(hide yes)
			(effects
				(font
					(size 1.27 1.016)
					(thickness 0.1524)
				)
			)
		)
		(duplicate_pad_numbers_are_jumpers no)
		(fp_line
			(start 0.889 -1.7018)
			(end -0.889 -1.7018)
			(stroke
				(width 0.1524)
				(type default)
			)
			(layer "F.SilkS")
		)
		(fp_line
			(start 0.889 -1.7018)
			(end 0.889 -0.381)
			(stroke
				(width 0.1524)
				(type default)
			)
			(layer "F.SilkS")
		)
		(fp_line
			(start -0.889 -1.7018)
			(end -0.889 0.2794)
			(stroke
				(width 0.1524)
				(type default)
			)
			(layer "F.SilkS")
		)
		(fp_line
			(start -0.889 0.0762)
			(end -0.889 1.7018)
			(stroke
				(width 0.1524)
				(type default)
			)
			(layer "F.SilkS")
		)
		(fp_line
			(start 0.889 1.7018)
			(end 0.889 -0.508)
			(stroke
				(width 0.1524)
				(type default)
			)
			(layer "F.SilkS")
		)
		(fp_line
			(start -0.889 1.7018)
			(end 0.889 1.7018)
			(stroke
				(width 0.1524)
				(type default)
			)
			(layer "F.SilkS")
		)
		(fp_poly
			(pts
				(xy 0.9652 -1.778) (xy 0.9652 1.778) (xy -0.9652 1.778) (xy -0.9652 -1.778)
			)
			(stroke
				(width 0)
				(type default)
			)
			(fill no)
			(layer "F.CrtYd")
		)
		(fp_rect
			(start -0.9652 1.778)
			(end 0.9652 -1.778)
			(stroke
				(width 0)
				(type default)
			)
			(fill no)
			(layer "F.Fab")
		)
		(pad "1" smd rect
			(at 0 -0.9652 90)
			(size 1.397 1.143)
			(layers "F.Cu" "F.Mask" "F.Paste")
			(net "P3V3_SNB")
		)
		(pad "2" smd rect
			(at 0 0.9652 90)
			(size 1.397 1.143)
			(layers "F.Cu" "F.Mask" "F.Paste")
			(net "GND")
		)
	)
)
